(kicad_pcb
	(version 20260206)
	(generator "pcbnew")
	(generator_version "10.0")
	(general
		(thickness 1.6)
		(legacy_teardrops no)
	)
	(paper "A4")
	(title_block
		(title "03242023_DA0F0TMBIJ0_F0T_Motherboard_J_brd_V01_OCP.brd")
		(comment 1 "Grand Teton / footprints 1176-1180 of 6105")
	)
	(layers
		(0 "F.Cu" signal "TOP")
		(4 "In1.Cu" signal "GND")
		(6 "In2.Cu" signal "IN1")
		(8 "In3.Cu" signal "GND1")
		(10 "In4.Cu" signal "IN2")
		(12 "In5.Cu" signal "GND2")
		(14 "In6.Cu" signal "IN3")
		(16 "In7.Cu" signal "GND3")
		(18 "In8.Cu" signal "VCC")
		(20 "In9.Cu" signal "VCC1")
		(22 "In10.Cu" signal "GND4")
		(24 "In11.Cu" signal "IN4")
		(26 "In12.Cu" signal "GND5")
		(28 "In13.Cu" signal "IN5")
		(30 "In14.Cu" signal "GND6")
		(32 "In15.Cu" signal "IN6")
		(34 "In16.Cu" signal "GND7")
		(2 "B.Cu" signal "BOTTOM")
		(9 "F.Adhes" user "F.Adhesive")
		(11 "B.Adhes" user "B.Adhesive")
		(13 "F.Paste" user "Package Geometry/Pastemask Top")
		(15 "B.Paste" user "Package Geometry/Pastemask Bottom")
		(5 "F.SilkS" user "Ref Des/Silkscreen Top")
		(7 "B.SilkS" user "Ref Des/Silkscreen Bottom")
		(1 "F.Mask" user "Board Geometry/Soldermask Top")
		(3 "B.Mask" user "Board Geometry/Soldermask Bottom")
		(17 "Dwgs.User" user "User.Drawings")
		(19 "Cmts.User" user "User.Comments")
		(21 "Eco1.User" user "User.Eco1")
		(23 "Eco2.User" user "User.Eco2")
		(25 "Edge.Cuts" user "Board Geometry/Outline")
		(27 "Margin" user)
		(31 "F.CrtYd" user "Package Geometry/Place Bound Top")
		(29 "B.CrtYd" user "Package Geometry/Place Bound Bottom")
		(35 "F.Fab" user "Ref Des/Assembly Top")
		(33 "B.Fab" user "Ref Des/Assembly Bottom")
	)
	(footprint ""
		(layer "F.Cu")
		(at 336.018124 -26.856182 -90)
		(property "Reference" "R1961"
			(at 0 0 270)
			(layer "F.SilkS")
			(hide yes)
			(effects
				(font
					(size 1.27 1.27)
				)
			)
		)
		(property "Value" ""
			(at 0 0 270)
			(layer "F.Fab")
			(effects
				(font
					(size 1.27 1.27)
				)
			)
		)
		(duplicate_pad_numbers_are_jumpers no)
		(fp_line
			(start -0.7874 0.4064)
			(end -0.7874 -0.4064)
			(stroke
				(width 0.1524)
				(type default)
			)
			(layer "F.SilkS")
		)
		(fp_line
			(start 0.7874 0.4064)
			(end -0.7874 0.4064)
			(stroke
				(width 0.1524)
				(type default)
			)
			(layer "F.SilkS")
		)
		(fp_line
			(start -0.7874 -0.4064)
			(end 0.7874 -0.4064)
			(stroke
				(width 0.1524)
				(type default)
			)
			(layer "F.SilkS")
		)
		(fp_line
			(start 0.7874 -0.4064)
			(end 0.7874 0.4064)
			(stroke
				(width 0.1524)
				(type default)
			)
			(layer "F.SilkS")
		)
		(fp_line
			(start -0.67945 0.3048)
			(end -0.67945 -0.305054)
			(stroke
				(width 0.1)
				(type default)
			)
			(layer "F.Fab")
		)
		(fp_line
			(start -0.12065 0.3048)
			(end -0.67945 0.3048)
			(stroke
				(width 0.1)
				(type default)
			)
			(layer "F.Fab")
		)
		(fp_line
			(start 0.120396 0.3048)
			(end 0.120396 0.2794)
			(stroke
				(width 0.1)
				(type default)
			)
			(layer "F.Fab")
		)
		(fp_line
			(start 0.67945 0.3048)
			(end 0.120396 0.3048)
			(stroke
				(width 0.1)
				(type default)
			)
			(layer "F.Fab")
		)
		(fp_line
			(start -0.12065 0.2794)
			(end -0.12065 0.3048)
			(stroke
				(width 0.1)
				(type default)
			)
			(layer "F.Fab")
		)
		(fp_line
			(start 0.120396 0.2794)
			(end -0.12065 0.2794)
			(stroke
				(width 0.1)
				(type default)
			)
			(layer "F.Fab")
		)
		(fp_line
			(start -0.12065 -0.2794)
			(end 0.12065 -0.2794)
			(stroke
				(width 0.1)
				(type default)
			)
			(layer "F.Fab")
		)
		(fp_line
			(start 0.12065 -0.2794)
			(end 0.12065 -0.3048)
			(stroke
				(width 0.1)
				(type default)
			)
			(layer "F.Fab")
		)
		(fp_line
			(start 0.12065 -0.3048)
			(end 0.67945 -0.3048)
			(stroke
				(width 0.1)
				(type default)
			)
			(layer "F.Fab")
		)
		(fp_line
			(start 0.67945 -0.3048)
			(end 0.67945 0.3048)
			(stroke
				(width 0.1)
				(type default)
			)
			(layer "F.Fab")
		)
		(fp_line
			(start -0.67945 -0.305054)
			(end -0.12065 -0.305054)
			(stroke
				(width 0.1)
				(type default)
			)
			(layer "F.Fab")
		)
		(fp_line
			(start -0.12065 -0.305054)
			(end -0.12065 -0.2794)
			(stroke
				(width 0.1)
				(type default)
			)
			(layer "F.Fab")
		)
		(pad "1" smd circle
			(at -0.40005 0 270)
			(size 0 0)
			(layers "F.Cu" "F.Mask" "F.Paste")
			(net "PGPPA_AUX")
		)
		(pad "2" smd circle
			(at 0.40005 0 270)
			(size 0 0)
			(layers "F.Cu" "F.Mask" "F.Paste")
			(net "ESPI_LFRAME_N_BMC_CS0_N")
		)
	)
	(footprint ""
		(layer "F.Cu")
		(at 65.52946 -379.03912)
		(property "Reference" "ME12"
			(at -9.652 -9.540748 0)
			(unlocked yes)
			(layer "F.SilkS")
			(effects
				(font
					(size 0.7874 0.5842)
					(thickness 0.1524)
				)
				(justify left)
			)
		)
		(property "Value" ""
			(at 0 0 0)
			(layer "F.Fab")
			(effects
				(font
					(size 1.27 1.27)
				)
			)
		)
		(duplicate_pad_numbers_are_jumpers no)
		(zone
			(layer "F.Cu")
			(hatch none 0.5)
			(connect_pads
				(clearance 0)
			)
			(min_thickness 0.25)
			(keepout
				(tracks allowed)
				(vias allowed)
				(pads allowed)
				(copperpour allowed)
				(footprints not_allowed)
			)
			(placement
				(enabled no)
				(sheetname "")
			)
			(fill
				(thermal_gap 0.5)
				(thermal_bridge_width 0.5)
				(island_removal_mode 0)
			)
			(polygon
				(pts
					(arc
						(start 75.52944 -379.03912)
						(mid 55.52948 -379.03912)
						(end 75.52944 -379.03912)
					)
				)
			)
		)
	)
	(footprint ""
		(layer "F.Cu")
		(at 308.33314 -433.12461 90)
		(property "Reference" "R4123"
			(at 0 0 90)
			(layer "F.SilkS")
			(hide yes)
			(effects
				(font
					(size 1.27 1.27)
				)
			)
		)
		(property "Value" ""
			(at 0 0 90)
			(layer "F.Fab")
			(effects
				(font
					(size 1.27 1.27)
				)
			)
		)
		(duplicate_pad_numbers_are_jumpers no)
		(fp_line
			(start 0.7874 -0.4064)
			(end 0.7874 0.4064)
			(stroke
				(width 0.1524)
				(type default)
			)
			(layer "F.SilkS")
		)
		(fp_line
			(start -0.7874 -0.4064)
			(end 0.7874 -0.4064)
			(stroke
				(width 0.1524)
				(type default)
			)
			(layer "F.SilkS")
		)
		(fp_line
			(start 0.7874 0.4064)
			(end -0.7874 0.4064)
			(stroke
				(width 0.1524)
				(type default)
			)
			(layer "F.SilkS")
		)
		(fp_line
			(start -0.7874 0.4064)
			(end -0.7874 -0.4064)
			(stroke
				(width 0.1524)
				(type default)
			)
			(layer "F.SilkS")
		)
		(fp_line
			(start -0.12065 -0.305054)
			(end -0.12065 -0.2794)
			(stroke
				(width 0.1)
				(type default)
			)
			(layer "F.Fab")
		)
		(fp_line
			(start -0.67945 -0.305054)
			(end -0.12065 -0.305054)
			(stroke
				(width 0.1)
				(type default)
			)
			(layer "F.Fab")
		)
		(fp_line
			(start 0.67945 -0.3048)
			(end 0.67945 0.3048)
			(stroke
				(width 0.1)
				(type default)
			)
			(layer "F.Fab")
		)
		(fp_line
			(start 0.12065 -0.3048)
			(end 0.67945 -0.3048)
			(stroke
				(width 0.1)
				(type default)
			)
			(layer "F.Fab")
		)
		(fp_line
			(start 0.12065 -0.2794)
			(end 0.12065 -0.3048)
			(stroke
				(width 0.1)
				(type default)
			)
			(layer "F.Fab")
		)
		(fp_line
			(start -0.12065 -0.2794)
			(end 0.12065 -0.2794)
			(stroke
				(width 0.1)
				(type default)
			)
			(layer "F.Fab")
		)
		(fp_line
			(start 0.120396 0.2794)
			(end -0.12065 0.2794)
			(stroke
				(width 0.1)
				(type default)
			)
			(layer "F.Fab")
		)
		(fp_line
			(start -0.12065 0.2794)
			(end -0.12065 0.3048)
			(stroke
				(width 0.1)
				(type default)
			)
			(layer "F.Fab")
		)
		(fp_line
			(start 0.67945 0.3048)
			(end 0.120396 0.3048)
			(stroke
				(width 0.1)
				(type default)
			)
			(layer "F.Fab")
		)
		(fp_line
			(start 0.120396 0.3048)
			(end 0.120396 0.2794)
			(stroke
				(width 0.1)
				(type default)
			)
			(layer "F.Fab")
		)
		(fp_line
			(start -0.12065 0.3048)
			(end -0.67945 0.3048)
			(stroke
				(width 0.1)
				(type default)
			)
			(layer "F.Fab")
		)
		(fp_line
			(start -0.67945 0.3048)
			(end -0.67945 -0.305054)
			(stroke
				(width 0.1)
				(type default)
			)
			(layer "F.Fab")
		)
		(pad "1" smd circle
			(at -0.40005 0 90)
			(size 0 0)
			(layers "F.Cu" "F.Mask" "F.Paste")
			(net "P3V3_AUX")
		)
		(pad "2" smd circle
			(at 0.40005 0 90)
			(size 0 0)
			(layers "F.Cu" "F.Mask" "F.Paste")
			(net "GPU_3V3IO_RSVD1_FFU")
		)
	)
	(footprint ""
		(layer "F.Cu")
		(at 19.707352 -167.170608 90)
		(property "Reference" "C1337"
			(at 0 0 90)
			(layer "F.SilkS")
			(hide yes)
			(effects
				(font
					(size 1.27 1.27)
				)
			)
		)
		(property "Value" ""
			(at 0 0 90)
			(layer "F.Fab")
			(effects
				(font
					(size 1.27 1.27)
				)
			)
		)
		(duplicate_pad_numbers_are_jumpers no)
		(fp_line
			(start 0.7874 -0.4064)
			(end 0.7874 0.4064)
			(stroke
				(width 0.1524)
				(type default)
			)
			(layer "F.SilkS")
		)
		(fp_line
			(start -0.7874 -0.4064)
			(end 0.7874 -0.4064)
			(stroke
				(width 0.1524)
				(type default)
			)
			(layer "F.SilkS")
		)
		(fp_line
			(start 0.7874 0.4064)
			(end -0.7874 0.4064)
			(stroke
				(width 0.1524)
				(type default)
			)
			(layer "F.SilkS")
		)
		(fp_line
			(start -0.7874 0.4064)
			(end -0.7874 -0.4064)
			(stroke
				(width 0.1524)
				(type default)
			)
			(layer "F.SilkS")
		)
		(fp_line
			(start -0.12065 -0.305054)
			(end -0.12065 -0.2794)
			(stroke
				(width 0.1)
				(type default)
			)
			(layer "F.Fab")
		)
		(fp_line
			(start -0.67945 -0.305054)
			(end -0.12065 -0.305054)
			(stroke
				(width 0.1)
				(type default)
			)
			(layer "F.Fab")
		)
		(fp_line
			(start 0.67945 -0.3048)
			(end 0.67945 0.3048)
			(stroke
				(width 0.1)
				(type default)
			)
			(layer "F.Fab")
		)
		(fp_line
			(start 0.12065 -0.3048)
			(end 0.67945 -0.3048)
			(stroke
				(width 0.1)
				(type default)
			)
			(layer "F.Fab")
		)
		(fp_line
			(start 0.12065 -0.2794)
			(end 0.12065 -0.3048)
			(stroke
				(width 0.1)
				(type default)
			)
			(layer "F.Fab")
		)
		(fp_line
			(start -0.12065 -0.2794)
			(end 0.12065 -0.2794)
			(stroke
				(width 0.1)
				(type default)
			)
			(layer "F.Fab")
		)
		(fp_line
			(start 0.120396 0.2794)
			(end -0.12065 0.2794)
			(stroke
				(width 0.1)
				(type default)
			)
			(layer "F.Fab")
		)
		(fp_line
			(start -0.12065 0.2794)
			(end -0.12065 0.3048)
			(stroke
				(width 0.1)
				(type default)
			)
			(layer "F.Fab")
		)
		(fp_line
			(start 0.67945 0.3048)
			(end 0.120396 0.3048)
			(stroke
				(width 0.1)
				(type default)
			)
			(layer "F.Fab")
		)
		(fp_line
			(start 0.120396 0.3048)
			(end 0.120396 0.2794)
			(stroke
				(width 0.1)
				(type default)
			)
			(layer "F.Fab")
		)
		(fp_line
			(start -0.12065 0.3048)
			(end -0.67945 0.3048)
			(stroke
				(width 0.1)
				(type default)
			)
			(layer "F.Fab")
		)
		(fp_line
			(start -0.67945 0.3048)
			(end -0.67945 -0.305054)
			(stroke
				(width 0.1)
				(type default)
			)
			(layer "F.Fab")
		)
		(pad "1" smd circle
			(at -0.40005 0 90)
			(size 0 0)
			(layers "F.Cu" "F.Mask" "F.Paste")
			(net "PVNN_TERM_CPU1")
		)
		(pad "2" smd circle
			(at 0.40005 0 90)
			(size 0 0)
			(layers "F.Cu" "F.Mask" "F.Paste")
			(net "GND")
		)
	)
	(footprint ""
		(layer "F.Cu")
		(at 360.544618 -343.902284 90)
		(property "Reference" "PC315"
			(at 0 0 90)
			(layer "F.SilkS")
			(hide yes)
			(effects
				(font
					(size 1.27 1.27)
				)
			)
		)
		(property "Value" ""
			(at 0 0 90)
			(layer "F.Fab")
			(effects
				(font
					(size 1.27 1.27)
				)
			)
		)
		(duplicate_pad_numbers_are_jumpers no)
		(fp_line
			(start -3.400044 1.249934)
			(end 3.400044 1.249934)
			(stroke
				(width 0.1524)
				(type default)
			)
			(layer "F.SilkS")
		)
		(fp_circle
			(center 0 1.249934)
			(end 0 4.649978)
			(stroke
				(width 0.1524)
				(type default)
			)
			(fill no)
			(layer "F.SilkS")
		)
		(fp_poly
			(pts
				(arc
					(start -3.400044 1.249934)
					(mid 0 4.649978)
					(end 3.400044 1.249934)
				)
			)
			(stroke
				(width 0)
				(type default)
			)
			(fill yes)
			(layer "F.SilkS")
		)
		(fp_circle
			(center 0 1.249934)
			(end 0 4.649978)
			(stroke
				(width 0.1)
				(type default)
			)
			(fill no)
			(layer "F.Fab")
		)
		(pad "1" thru_hole rect
			(at 0 0 90)
			(size 1.524 1.524)
			(drill 1.016)
			(layers "*.Cu" "*.Mask")
			(remove_unused_layers no)
			(net "SW_P12V_PVCCIN_CPU0_FLT")
			(clearance 0)
			(padstack
				(mode front_inner_back)
				(layer "Inner"
					(shape circle)
					(size 1.524 1.524)
					(clearance 0)
				)
				(layer "B.Cu"
					(shape rect)
					(size 1.524 1.524)
					(clearance 0)
				)
			)
		)
		(pad "2" thru_hole circle
			(at 0 2.500122 90)
			(size 1.524 1.524)
			(drill 1.016)
			(layers "*.Cu" "*.Mask")
			(remove_unused_layers no)
			(net "GND")
			(clearance 0)
		)
	)
)
